# SCM (Grand Teton) — schematic netlist excerpt (pin names and nets, part order shuffled) for the footprints in the layout excerpt that follows; sources: Cadence DE-HDL packaged netlist, KiCad conversion of 12092022_DA0F0TMDCD0_F0T_Management_Board_D_brd_V3_OCP.brd

R418  Q_RES  4.7K 1% EMPTY  pkg 0402LF  page 26 : A = P3V3_AUX ; B = TMC75_A2
C190  Q_CAP  0.1UF 25V 10% X7R  pkg 0402  page 41 : A = PVCCA_AUX_PLD ; B = GND

(kicad_pcb
	(version 20260206)
	(generator "pcbnew")
	(generator_version "10.0")
	(general
		(thickness 1.6)
		(legacy_teardrops no)
	)
	(paper "A4")
	(title_block
		(title "12092022_DA0F0TMDCD0_F0T_Management_Board_D_brd_V3_OCP.brd")
		(comment 1 "Grand Teton / footprints 1249-1250 of 1440")
	)
	(layers
		(0 "F.Cu" signal "TOP")
		(4 "In1.Cu" signal "GND")
		(6 "In2.Cu" signal "IN1")
		(8 "In3.Cu" signal "GND1")
		(10 "In4.Cu" signal "IN2")
		(12 "In5.Cu" signal "VCC")
		(14 "In6.Cu" signal "VCC1")
		(16 "In7.Cu" signal "IN3")
		(18 "In8.Cu" signal "GND2")
		(20 "In9.Cu" signal "IN4")
		(22 "In10.Cu" signal "GND3")
		(2 "B.Cu" signal "BOTTOM")
		(9 "F.Adhes" user "F.Adhesive")
		(11 "B.Adhes" user "B.Adhesive")
		(13 "F.Paste" user "Package Geometry/Pastemask Top")
		(15 "B.Paste" user "Package Geometry/Pastemask Bottom")
		(5 "F.SilkS" user "Ref Des/Silkscreen Top")
		(7 "B.SilkS" user "Ref Des/Silkscreen Bottom")
		(1 "F.Mask" user "Board Geometry/Soldermask Top")
		(3 "B.Mask" user "Board Geometry/Soldermask Bottom")
		(17 "Dwgs.User" user "User.Drawings")
		(19 "Cmts.User" user "User.Comments")
		(21 "Eco1.User" user "User.Eco1")
		(23 "Eco2.User" user "User.Eco2")
		(25 "Edge.Cuts" user "Board Geometry/Outline")
		(27 "Margin" user)
		(31 "F.CrtYd" user "Package Geometry/Place Bound Top")
		(29 "B.CrtYd" user "Package Geometry/Place Bound Bottom")
		(35 "F.Fab" user "Ref Des/Assembly Top")
		(33 "B.Fab" user "Ref Des/Assembly Bottom")
	)
	(footprint ""
		(layer "B.Cu")
		(at 15.621 -88.5952 -135)
		(property "Reference" "C190"
			(at 0 0 45)
			(layer "B.SilkS")
			(hide yes)
			(effects
				(font
					(size 1.27 1.27)
				)
				(justify mirror)
			)
		)
		(property "Value" ""
			(at 0 0 45)
			(layer "B.Fab")
			(effects
				(font
					(size 1.27 1.27)
				)
				(justify mirror)
			)
		)
		(duplicate_pad_numbers_are_jumpers no)
		(fp_line
			(start 0.787389 0.406267)
			(end 0.787389 -0.406267)
			(stroke
				(width 0.1524)
				(type default)
			)
			(layer "B.SilkS")
		)
		(fp_line
			(start 0.787389 -0.406267)
			(end -0.787389 -0.406267)
			(stroke
				(width 0.1524)
				(type default)
			)
			(layer "B.SilkS")
		)
		(fp_line
			(start -0.787389 0.406267)
			(end 0.787389 0.406267)
			(stroke
				(width 0.1524)
				(type default)
			)
			(layer "B.SilkS")
		)
		(fp_line
			(start -0.787389 -0.406267)
			(end -0.787389 0.406267)
			(stroke
				(width 0.1524)
				(type default)
			)
			(layer "B.SilkS")
		)
		(fp_line
			(start 0.679446 0.30479)
			(end 0.679446 -0.305149)
			(stroke
				(width 0.1)
				(type default)
			)
			(layer "B.Fab")
		)
		(fp_line
			(start 0.120515 0.30479)
			(end 0.679446 0.30479)
			(stroke
				(width 0.1)
				(type default)
			)
			(layer "B.Fab")
		)
		(fp_line
			(start 0.120695 0.279466)
			(end 0.120515 0.30479)
			(stroke
				(width 0.1)
				(type default)
			)
			(layer "B.Fab")
		)
		(fp_line
			(start 0.679446 -0.305149)
			(end 0.120695 -0.304969)
			(stroke
				(width 0.1)
				(type default)
			)
			(layer "B.Fab")
		)
		(fp_line
			(start -0.120515 0.30479)
			(end -0.120335 0.279466)
			(stroke
				(width 0.1)
				(type default)
			)
			(layer "B.Fab")
		)
		(fp_line
			(start -0.120335 0.279466)
			(end 0.120695 0.279466)
			(stroke
				(width 0.1)
				(type default)
			)
			(layer "B.Fab")
		)
		(fp_line
			(start 0.120695 -0.279466)
			(end -0.120695 -0.279466)
			(stroke
				(width 0.1)
				(type default)
			)
			(layer "B.Fab")
		)
		(fp_line
			(start 0.120695 -0.304969)
			(end 0.120695 -0.279466)
			(stroke
				(width 0.1)
				(type default)
			)
			(layer "B.Fab")
		)
		(fp_line
			(start -0.679446 0.30479)
			(end -0.120515 0.30479)
			(stroke
				(width 0.1)
				(type default)
			)
			(layer "B.Fab")
		)
		(fp_line
			(start -0.120695 -0.279466)
			(end -0.120515 -0.30479)
			(stroke
				(width 0.1)
				(type default)
			)
			(layer "B.Fab")
		)
		(fp_line
			(start -0.120515 -0.30479)
			(end -0.679446 -0.30479)
			(stroke
				(width 0.1)
				(type default)
			)
			(layer "B.Fab")
		)
		(fp_line
			(start -0.679446 -0.30479)
			(end -0.679446 0.30479)
			(stroke
				(width 0.1)
				(type default)
			)
			(layer "B.Fab")
		)
		(pad "1" smd circle
			(at 0.40005 0 45)
			(size 0 0)
			(layers "B.Cu" "B.Mask" "B.Paste")
			(net "PVCCA_AUX_PLD")
		)
		(pad "2" smd circle
			(at -0.40005 0 45)
			(size 0 0)
			(layers "B.Cu" "B.Mask" "B.Paste")
			(net "GND")
		)
	)
	(footprint ""
		(layer "B.Cu")
		(at 25.019 -18.034 -90)
		(property "Reference" "R418"
			(at 0 0 90)
			(layer "B.SilkS")
			(hide yes)
			(effects
				(font
					(size 1.27 1.27)
				)
				(justify mirror)
			)
		)
		(property "Value" ""
			(at 0 0 90)
			(layer "B.Fab")
			(effects
				(font
					(size 1.27 1.27)
				)
				(justify mirror)
			)
		)
		(duplicate_pad_numbers_are_jumpers no)
		(fp_line
			(start -0.7874 0.4064)
			(end 0.7874 0.4064)
			(stroke
				(width 0.1524)
				(type default)
			)
			(layer "B.SilkS")
		)
		(fp_line
			(start 0.7874 0.4064)
			(end 0.7874 -0.4064)
			(stroke
				(width 0.1524)
				(type default)
			)
			(layer "B.SilkS")
		)
		(fp_line
			(start -0.7874 -0.4064)
			(end -0.7874 0.4064)
			(stroke
				(width 0.1524)
				(type default)
			)
			(layer "B.SilkS")
		)
		(fp_line
			(start 0.7874 -0.4064)
			(end -0.7874 -0.4064)
			(stroke
				(width 0.1524)
				(type default)
			)
			(layer "B.SilkS")
		)
		(fp_line
			(start -0.67945 0.3048)
			(end -0.120396 0.3048)
			(stroke
				(width 0.1)
				(type default)
			)
			(layer "B.Fab")
		)
		(fp_line
			(start -0.120396 0.3048)
			(end -0.120396 0.2794)
			(stroke
				(width 0.1)
				(type default)
			)
			(layer "B.Fab")
		)
		(fp_line
			(start 0.12065 0.3048)
			(end 0.67945 0.3048)
			(stroke
				(width 0.1)
				(type default)
			)
			(layer "B.Fab")
		)
		(fp_line
			(start 0.67945 0.3048)
			(end 0.67945 -0.305054)
			(stroke
				(width 0.1)
				(type default)
			)
			(layer "B.Fab")
		)
		(fp_line
			(start -0.120396 0.2794)
			(end 0.12065 0.2794)
			(stroke
				(width 0.1)
				(type default)
			)
			(layer "B.Fab")
		)
		(fp_line
			(start 0.12065 0.2794)
			(end 0.12065 0.3048)
			(stroke
				(width 0.1)
				(type default)
			)
			(layer "B.Fab")
		)
		(fp_line
			(start -0.12065 -0.2794)
			(end -0.12065 -0.3048)
			(stroke
				(width 0.1)
				(type default)
			)
			(layer "B.Fab")
		)
		(fp_line
			(start 0.12065 -0.2794)
			(end -0.12065 -0.2794)
			(stroke
				(width 0.1)
				(type default)
			)
			(layer "B.Fab")
		)
		(fp_line
			(start -0.67945 -0.3048)
			(end -0.67945 0.3048)
			(stroke
				(width 0.1)
				(type default)
			)
			(layer "B.Fab")
		)
		(fp_line
			(start -0.12065 -0.3048)
			(end -0.67945 -0.3048)
			(stroke
				(width 0.1)
				(type default)
			)
			(layer "B.Fab")
		)
		(fp_line
			(start 0.12065 -0.305054)
			(end 0.12065 -0.2794)
			(stroke
				(width 0.1)
				(type default)
			)
			(layer "B.Fab")
		)
		(fp_line
			(start 0.67945 -0.305054)
			(end 0.12065 -0.305054)
			(stroke
				(width 0.1)
				(type default)
			)
			(layer "B.Fab")
		)
		(pad "1" smd circle
			(at 0.40005 0 90)
			(size 0 0)
			(layers "B.Cu" "B.Mask" "B.Paste")
			(net "P3V3_AUX")
		)
		(pad "2" smd circle
			(at -0.40005 0 90)
			(size 0 0)
			(layers "B.Cu" "B.Mask" "B.Paste")
			(net "TMC75_A2")
		)
	)
)
